# T6G (Grand Teton) — schematic netlist excerpt (pin names and nets, part order shuffled) for the footprints in the layout excerpt that follows; sources: Cadence DE-HDL packaged netlist, KiCad conversion of 04192023_DAF0TMB3IC0_F0TG_MB_C_brd_V02_OCP.brd

R195  Q_RES  33 5% CHIP  pkg 0402LF  page 81 : A = FM_CPU1_PWRGD_OUT ; B = CPU1_PWRGD_OUT
R3773  Q_RES  4.7K 5% EMPTY  pkg 0402LF  page 145 : A = P3V3_AUX ; B = RST_SMB_E1S_0_N

(kicad_pcb
	(version 20260206)
	(generator "pcbnew")
	(generator_version "10.0")
	(general
		(thickness 1.6)
		(legacy_teardrops no)
	)
	(paper "A4")
	(title_block
		(title "04192023_DAF0TMB3IC0_F0TG_MB_C_brd_V02_OCP.brd")
		(comment 1 "Grand Teton / footprints 2894-2895 of 8354")
	)
	(layers
		(0 "F.Cu" signal "TOP")
		(4 "In1.Cu" signal "GND")
		(6 "In2.Cu" signal "IN1")
		(8 "In3.Cu" signal "GND1")
		(10 "In4.Cu" signal "IN2")
		(12 "In5.Cu" signal "GND2")
		(14 "In6.Cu" signal "IN3")
		(16 "In7.Cu" signal "GND3")
		(18 "In8.Cu" signal "VCC")
		(20 "In9.Cu" signal "VCC1")
		(22 "In10.Cu" signal "GND4")
		(24 "In11.Cu" signal "IN4")
		(26 "In12.Cu" signal "GND5")
		(28 "In13.Cu" signal "IN5")
		(30 "In14.Cu" signal "GND6")
		(32 "In15.Cu" signal "IN6")
		(34 "In16.Cu" signal "GND7")
		(2 "B.Cu" signal "BOTTOM")
		(9 "F.Adhes" user "F.Adhesive")
		(11 "B.Adhes" user "B.Adhesive")
		(13 "F.Paste" user "Package Geometry/Pastemask Top")
		(15 "B.Paste" user "Package Geometry/Pastemask Bottom")
		(5 "F.SilkS" user "Ref Des/Silkscreen Top")
		(7 "B.SilkS" user "Ref Des/Silkscreen Bottom")
		(1 "F.Mask" user "Board Geometry/Soldermask Top")
		(3 "B.Mask" user "Board Geometry/Soldermask Bottom")
		(17 "Dwgs.User" user "User.Drawings")
		(19 "Cmts.User" user "User.Comments")
		(21 "Eco1.User" user "User.Eco1")
		(23 "Eco2.User" user "User.Eco2")
		(25 "Edge.Cuts" user "Board Geometry/Outline")
		(27 "Margin" user)
		(31 "F.CrtYd" user "Package Geometry/Place Bound Top")
		(29 "B.CrtYd" user "Package Geometry/Place Bound Bottom")
		(35 "F.Fab" user "Ref Des/Assembly Top")
		(33 "B.Fab" user "Ref Des/Assembly Bottom")
	)
	(footprint ""
		(layer "F.Cu")
		(at 208.894426 -115.657376)
		(property "Reference" "R195"
			(at 0 0 0)
			(layer "F.SilkS")
			(hide yes)
			(effects
				(font
					(size 1.27 1.27)
				)
			)
		)
		(property "Value" ""
			(at 0 0 0)
			(layer "F.Fab")
			(effects
				(font
					(size 1.27 1.27)
				)
			)
		)
		(duplicate_pad_numbers_are_jumpers no)
		(fp_line
			(start -0.7874 -0.4064)
			(end 0.7874 -0.4064)
			(stroke
				(width 0.1524)
				(type default)
			)
			(layer "F.SilkS")
		)
		(fp_line
			(start -0.7874 0.4064)
			(end -0.7874 -0.4064)
			(stroke
				(width 0.1524)
				(type default)
			)
			(layer "F.SilkS")
		)
		(fp_line
			(start 0.7874 -0.4064)
			(end 0.7874 0.4064)
			(stroke
				(width 0.1524)
				(type default)
			)
			(layer "F.SilkS")
		)
		(fp_line
			(start 0.7874 0.4064)
			(end -0.7874 0.4064)
			(stroke
				(width 0.1524)
				(type default)
			)
			(layer "F.SilkS")
		)
		(fp_line
			(start -0.67945 -0.305054)
			(end -0.12065 -0.305054)
			(stroke
				(width 0.1)
				(type default)
			)
			(layer "F.Fab")
		)
		(fp_line
			(start -0.67945 0.3048)
			(end -0.67945 -0.305054)
			(stroke
				(width 0.1)
				(type default)
			)
			(layer "F.Fab")
		)
		(fp_line
			(start -0.12065 -0.305054)
			(end -0.12065 -0.2794)
			(stroke
				(width 0.1)
				(type default)
			)
			(layer "F.Fab")
		)
		(fp_line
			(start -0.12065 -0.2794)
			(end 0.12065 -0.2794)
			(stroke
				(width 0.1)
				(type default)
			)
			(layer "F.Fab")
		)
		(fp_line
			(start -0.12065 0.2794)
			(end -0.12065 0.3048)
			(stroke
				(width 0.1)
				(type default)
			)
			(layer "F.Fab")
		)
		(fp_line
			(start -0.12065 0.3048)
			(end -0.67945 0.3048)
			(stroke
				(width 0.1)
				(type default)
			)
			(layer "F.Fab")
		)
		(fp_line
			(start 0.120396 0.2794)
			(end -0.12065 0.2794)
			(stroke
				(width 0.1)
				(type default)
			)
			(layer "F.Fab")
		)
		(fp_line
			(start 0.120396 0.3048)
			(end 0.120396 0.2794)
			(stroke
				(width 0.1)
				(type default)
			)
			(layer "F.Fab")
		)
		(fp_line
			(start 0.12065 -0.3048)
			(end 0.67945 -0.3048)
			(stroke
				(width 0.1)
				(type default)
			)
			(layer "F.Fab")
		)
		(fp_line
			(start 0.12065 -0.2794)
			(end 0.12065 -0.3048)
			(stroke
				(width 0.1)
				(type default)
			)
			(layer "F.Fab")
		)
		(fp_line
			(start 0.67945 -0.3048)
			(end 0.67945 0.3048)
			(stroke
				(width 0.1)
				(type default)
			)
			(layer "F.Fab")
		)
		(fp_line
			(start 0.67945 0.3048)
			(end 0.120396 0.3048)
			(stroke
				(width 0.1)
				(type default)
			)
			(layer "F.Fab")
		)
		(pad "1" smd circle
			(at -0.40005 0)
			(size 0 0)
			(layers "F.Cu" "F.Mask" "F.Paste")
			(net "FM_CPU1_PWRGD_OUT")
		)
		(pad "2" smd circle
			(at 0.40005 0)
			(size 0 0)
			(layers "F.Cu" "F.Mask" "F.Paste")
			(net "CPU1_PWRGD_OUT")
		)
	)
	(footprint ""
		(layer "F.Cu")
		(at 261.468616 -75.770994 180)
		(property "Reference" "R3773"
			(at 0 0 180)
			(layer "F.SilkS")
			(hide yes)
			(effects
				(font
					(size 1.27 1.27)
				)
			)
		)
		(property "Value" ""
			(at 0 0 180)
			(layer "F.Fab")
			(effects
				(font
					(size 1.27 1.27)
				)
			)
		)
		(duplicate_pad_numbers_are_jumpers no)
		(fp_line
			(start 0.7874 0.4064)
			(end -0.7874 0.4064)
			(stroke
				(width 0.1524)
				(type default)
			)
			(layer "F.SilkS")
		)
		(fp_line
			(start 0.7874 -0.4064)
			(end 0.7874 0.4064)
			(stroke
				(width 0.1524)
				(type default)
			)
			(layer "F.SilkS")
		)
		(fp_line
			(start -0.7874 0.4064)
			(end -0.7874 -0.4064)
			(stroke
				(width 0.1524)
				(type default)
			)
			(layer "F.SilkS")
		)
		(fp_line
			(start -0.7874 -0.4064)
			(end 0.7874 -0.4064)
			(stroke
				(width 0.1524)
				(type default)
			)
			(layer "F.SilkS")
		)
		(fp_line
			(start 0.67945 0.3048)
			(end 0.120396 0.3048)
			(stroke
				(width 0.1)
				(type default)
			)
			(layer "F.Fab")
		)
		(fp_line
			(start 0.67945 -0.3048)
			(end 0.67945 0.3048)
			(stroke
				(width 0.1)
				(type default)
			)
			(layer "F.Fab")
		)
		(fp_line
			(start 0.12065 -0.2794)
			(end 0.12065 -0.3048)
			(stroke
				(width 0.1)
				(type default)
			)
			(layer "F.Fab")
		)
		(fp_line
			(start 0.12065 -0.3048)
			(end 0.67945 -0.3048)
			(stroke
				(width 0.1)
				(type default)
			)
			(layer "F.Fab")
		)
		(fp_line
			(start 0.120396 0.3048)
			(end 0.120396 0.2794)
			(stroke
				(width 0.1)
				(type default)
			)
			(layer "F.Fab")
		)
		(fp_line
			(start 0.120396 0.2794)
			(end -0.12065 0.2794)
			(stroke
				(width 0.1)
				(type default)
			)
			(layer "F.Fab")
		)
		(fp_line
			(start -0.12065 0.3048)
			(end -0.67945 0.3048)
			(stroke
				(width 0.1)
				(type default)
			)
			(layer "F.Fab")
		)
		(fp_line
			(start -0.12065 0.2794)
			(end -0.12065 0.3048)
			(stroke
				(width 0.1)
				(type default)
			)
			(layer "F.Fab")
		)
		(fp_line
			(start -0.12065 -0.2794)
			(end 0.12065 -0.2794)
			(stroke
				(width 0.1)
				(type default)
			)
			(layer "F.Fab")
		)
		(fp_line
			(start -0.12065 -0.305054)
			(end -0.12065 -0.2794)
			(stroke
				(width 0.1)
				(type default)
			)
			(layer "F.Fab")
		)
		(fp_line
			(start -0.67945 0.3048)
			(end -0.67945 -0.305054)
			(stroke
				(width 0.1)
				(type default)
			)
			(layer "F.Fab")
		)
		(fp_line
			(start -0.67945 -0.305054)
			(end -0.12065 -0.305054)
			(stroke
				(width 0.1)
				(type default)
			)
			(layer "F.Fab")
		)
		(pad "1" smd circle
			(at -0.40005 0 180)
			(size 0 0)
			(layers "F.Cu" "F.Mask" "F.Paste")
			(net "P3V3_AUX")
		)
		(pad "2" smd circle
			(at 0.40005 0 180)
			(size 0 0)
			(layers "F.Cu" "F.Mask" "F.Paste")
			(net "RST_SMB_E1S_0_N")
		)
	)
)
